(kicad_pcb
	(version 20260206)
	(generator "pcbnew")
	(generator_version "10.0")
	(general
		(thickness 1.6)
		(legacy_teardrops no)
	)
	(paper "A4")
	(title_block
		(title "Bryce Canyon_IOM_IOC_16318-2_OCP.brd")
		(comment 1 "Bryce Canyon / footprints 888-893 of 1605")
	)
	(layers
		(0 "F.Cu" signal "TOP")
		(4 "In1.Cu" signal "L2GND")
		(6 "In2.Cu" signal "L3")
		(8 "In3.Cu" signal "L4VCC")
		(10 "In4.Cu" signal "L5VCC")
		(12 "In5.Cu" signal "L6")
		(14 "In6.Cu" signal "L7GND")
		(2 "B.Cu" signal "BOTTOM")
		(9 "F.Adhes" user "F.Adhesive")
		(11 "B.Adhes" user "B.Adhesive")
		(13 "F.Paste" user "Package Geometry/Pastemask Top")
		(15 "B.Paste" user "Package Geometry/Pastemask Bottom")
		(5 "F.SilkS" user "Ref Des/Silkscreen Top")
		(7 "B.SilkS" user "Ref Des/Silkscreen Bottom")
		(1 "F.Mask" user "Board Geometry/Soldermask Top")
		(3 "B.Mask" user "Board Geometry/Soldermask Bottom")
		(17 "Dwgs.User" user "User.Drawings")
		(19 "Cmts.User" user "User.Comments")
		(21 "Eco1.User" user "User.Eco1")
		(23 "Eco2.User" user "User.Eco2")
		(25 "Edge.Cuts" user "Board Geometry/Outline")
		(27 "Margin" user)
		(31 "F.CrtYd" user "Package Geometry/Place Bound Top")
		(29 "B.CrtYd" user "Package Geometry/Place Bound Bottom")
		(35 "F.Fab" user "Ref Des/Assembly Top")
		(33 "B.Fab" user "Ref Des/Assembly Bottom")
	)
	(footprint ""
		(layer "F.Cu")
		(at 54.280054 -172.699934)
		(property "Reference" "TPM1"
			(at 0 0 0)
			(layer "F.SilkS")
			(hide yes)
			(effects
				(font
					(size 1.27 1.27)
				)
			)
		)
		(property "Value" "FCI-CONN11-2-GP"
			(at -7.4803 1.3589 0)
			(unlocked yes)
			(layer "F.Fab")
			(hide yes)
			(effects
				(font
					(size 1.016 1.016)
					(thickness 0.1524)
				)
			)
		)
		(property "Device Type" "91932-31111LF"
			(at -7.4803 -0.1651 0)
			(unlocked yes)
			(layer "F.Fab")
			(hide yes)
			(effects
				(font
					(size 1.016 1.016)
					(thickness 0.1524)
				)
			)
		)
		(duplicate_pad_numbers_are_jumpers no)
		(fp_line
			(start -5.4102 -3.556)
			(end -5.4102 3.556)
			(stroke
				(width 0.1524)
				(type default)
			)
			(layer "F.SilkS")
		)
		(fp_line
			(start -5.4102 3.556)
			(end 5.4102 3.556)
			(stroke
				(width 0.1524)
				(type default)
			)
			(layer "F.SilkS")
		)
		(fp_line
			(start -2.8321 3.6449)
			(end -2.2479 3.6449)
			(stroke
				(width 0.3302)
				(type default)
			)
			(layer "F.SilkS")
		)
		(fp_line
			(start 5.4102 -3.556)
			(end -5.4102 -3.556)
			(stroke
				(width 0.1524)
				(type default)
			)
			(layer "F.SilkS")
		)
		(fp_line
			(start 5.4102 3.556)
			(end 5.4102 -3.556)
			(stroke
				(width 0.1524)
				(type default)
			)
			(layer "F.SilkS")
		)
		(fp_poly
			(pts
				(xy -2.546096 3.612642) (xy -3.181096 4.247642) (xy -1.911096 4.247642)
			)
			(stroke
				(width 0)
				(type default)
			)
			(fill yes)
			(layer "F.SilkS")
		)
		(fp_poly
			(pts
				(xy -2.8067 1.08839)
				(arc
					(start -2.8067 -0.422402)
					(mid -2.451868 -0.675672)
					(end -2.3114 -1.08839)
				)
				(arc
					(start 2.3114 -1.08839)
					(mid 2.451818 -0.675634)
					(end 2.8067 -0.422402)
				)
				(xy 2.8067 1.08839)
			)
			(stroke
				(width 0)
				(type default)
			)
			(fill yes)
			(layer "F.SilkS")
		)
		(fp_rect
			(start -5.1562 2.794)
			(end 5.1562 -2.794)
			(stroke
				(width 0)
				(type default)
			)
			(fill no)
			(layer "F.CrtYd")
		)
		(fp_poly
			(pts
				(xy 5.6642 -2.794) (xy -5.1562 -2.794) (xy -5.1562 2.794) (xy 5.1562 2.794) (xy 5.1562 -2.7813)
				(xy 5.6642 -2.7813) (xy 5.6642 3.81) (xy -5.6642 3.81) (xy -5.6642 -3.81) (xy 5.6642 -3.81)
			)
			(stroke
				(width 0)
				(type default)
			)
			(fill no)
			(layer "F.CrtYd")
		)
		(fp_rect
			(start -5.6642 3.81)
			(end 5.6642 -3.81)
			(stroke
				(width 0)
				(type default)
			)
			(fill no)
			(layer "F.Fab")
		)
		(pad "" np_thru_hole circle
			(at -3.0226 -1.100074)
			(size 0.254 0.254)
			(drill 0.8128)
			(layers "*.Cu" "*.Mask")
			(clearance 0.635)
			(thermal_gap 0.635)
		)
		(pad "" np_thru_hole circle
			(at 3.0226 -1.100074)
			(size 0.254 0.254)
			(drill 0.8128)
			(layers "*.Cu" "*.Mask")
			(clearance 0.635)
			(thermal_gap 0.635)
		)
		(pad "1" smd rect
			(at -2.500122 2.29489)
			(size 0.6096 2.0066)
			(layers "F.Cu" "F.Mask" "F.Paste")
			(net "Net_358")
		)
		(pad "2" smd rect
			(at -1.500124 2.29489)
			(size 0.6096 2.0066)
			(layers "F.Cu" "F.Mask" "F.Paste")
			(net "Net_357")
		)
		(pad "3" smd rect
			(at -0.500126 2.29489)
			(size 0.6096 2.0066)
			(layers "F.Cu" "F.Mask" "F.Paste")
			(net "Net_356")
		)
		(pad "4" smd rect
			(at 0.500126 2.29489)
			(size 0.6096 2.0066)
			(layers "F.Cu" "F.Mask" "F.Paste")
			(net "Net_355")
		)
		(pad "5" smd rect
			(at 1.500124 2.29489)
			(size 0.6096 2.0066)
			(layers "F.Cu" "F.Mask" "F.Paste")
			(net "Net_354")
		)
		(pad "6" smd rect
			(at 2.500122 2.29489)
			(size 0.6096 2.0066)
			(layers "F.Cu" "F.Mask" "F.Paste")
			(net "I2C_TPM_SDA")
		)
		(pad "7" smd rect
			(at -1.999996 -2.29489)
			(size 0.6096 2.0066)
			(layers "F.Cu" "F.Mask" "F.Paste")
			(net "P3V3_STBY")
		)
		(pad "8" smd rect
			(at -0.999998 -2.29489)
			(size 0.6096 2.0066)
			(layers "F.Cu" "F.Mask" "F.Paste")
			(net "FM_TPM_PRSNT_RST_N")
		)
		(pad "9" smd rect
			(at 0 -2.29489)
			(size 0.6096 2.0066)
			(layers "F.Cu" "F.Mask" "F.Paste")
			(net "Net_359")
		)
		(pad "10" smd rect
			(at 0.999998 -2.29489)
			(size 0.6096 2.0066)
			(layers "F.Cu" "F.Mask" "F.Paste")
			(net "I2C_TPM_SCL")
		)
		(pad "11" smd rect
			(at 1.999996 -2.29489)
			(size 0.6096 2.0066)
			(layers "F.Cu" "F.Mask" "F.Paste")
			(net "GND")
		)
		(pad "G1" smd custom
			(at -4.219956 0)
			(size 0.34925 0.34925)
			(layers "F.Cu" "F.Mask" "F.Paste")
			(net "GND")
			(options
				(clearance outline)
				(anchor circle)
			)
			(primitives
				(gr_poly
					(pts
						(xy -0.6985 2.921) (xy -0.6985 -2.921) (xy 0.6985 -2.921)
						(arc
							(start 0.6985 -1.610106)
							(mid 0.482924 -1.100074)
							(end 0.6985 -0.590042)
						)
						(xy 0.6985 2.921)
					)
					(width 0)
					(fill yes)
				)
			)
		)
		(pad "G2" smd custom
			(at 4.219956 0)
			(size 0.34925 0.34925)
			(layers "F.Cu" "F.Mask" "F.Paste")
			(net "GND")
			(options
				(clearance outline)
				(anchor circle)
			)
			(primitives
				(gr_poly
					(pts
						(xy -0.6985 2.921)
						(arc
							(start -0.6985 -0.590042)
							(mid -0.482924 -1.100074)
							(end -0.6985 -1.610106)
						)
						(xy -0.6985 -2.921) (xy 0.6985 -2.921) (xy 0.6985 2.921)
					)
					(width 0)
					(fill yes)
				)
			)
		)
		(zone
			(layer "F.Cu")
			(hatch none 0.5)
			(connect_pads
				(clearance 0)
			)
			(min_thickness 0.25)
			(keepout
				(tracks not_allowed)
				(vias allowed)
				(pads allowed)
				(copperpour not_allowed)
				(footprints allowed)
			)
			(placement
				(enabled no)
				(sheetname "")
			)
			(fill
				(thermal_gap 0.5)
				(thermal_bridge_width 0.5)
				(island_removal_mode 0)
			)
			(polygon
				(pts
					(xy 51.473354 -171.408344) (xy 57.086754 -171.408344) (xy 57.086754 -173.991524) (xy 51.473354 -173.991524)
				)
			)
		)
		(zone
			(layer "F.Cu")
			(hatch none 0.5)
			(connect_pads
				(clearance 0)
			)
			(min_thickness 0.25)
			(keepout
				(tracks allowed)
				(vias not_allowed)
				(pads allowed)
				(copperpour not_allowed)
				(footprints allowed)
			)
			(placement
				(enabled no)
				(sheetname "")
			)
			(fill
				(thermal_gap 0.5)
				(thermal_bridge_width 0.5)
				(island_removal_mode 0)
			)
			(polygon
				(pts
					(xy 51.473354 -171.408344) (xy 57.086754 -171.408344) (xy 57.086754 -173.991524) (xy 51.473354 -173.991524)
				)
			)
		)
		(zone
			(layer "F.Cu")
			(hatch none 0.5)
			(connect_pads
				(clearance 0)
			)
			(min_thickness 0.25)
			(keepout
				(tracks allowed)
				(vias not_allowed)
				(pads allowed)
				(copperpour not_allowed)
				(footprints allowed)
			)
			(placement
				(enabled no)
				(sheetname "")
			)
			(fill
				(thermal_gap 0.5)
				(thermal_bridge_width 0.5)
				(island_removal_mode 0)
			)
			(polygon
				(pts
					(xy 51.473354 -171.408344) (xy 57.086754 -171.408344) (xy 57.086754 -171.916344) (xy 51.473354 -171.916344)
				)
			)
		)
		(zone
			(layer "F.Cu")
			(hatch none 0.5)
			(connect_pads
				(clearance 0)
			)
			(min_thickness 0.25)
			(keepout
				(tracks allowed)
				(vias not_allowed)
				(pads allowed)
				(copperpour not_allowed)
				(footprints allowed)
			)
			(placement
				(enabled no)
				(sheetname "")
			)
			(fill
				(thermal_gap 0.5)
				(thermal_bridge_width 0.5)
				(island_removal_mode 0)
			)
			(polygon
				(pts
					(xy 51.968654 -173.483524) (xy 56.591454 -173.483524) (xy 56.591454 -173.991524) (xy 51.968654 -173.991524)
				)
			)
		)
		(zone
			(layers "F.Cu" "B.Cu" "In1.Cu" "In2.Cu" "In3.Cu" "In4.Cu" "In5.Cu" "In6.Cu")
			(hatch none 0.5)
			(connect_pads
				(clearance 0)
			)
			(min_thickness 0.25)
			(keepout
				(tracks not_allowed)
				(vias allowed)
				(pads allowed)
				(copperpour not_allowed)
				(footprints allowed)
			)
			(placement
				(enabled no)
				(sheetname "")
			)
			(fill
				(thermal_gap 0.5)
				(thermal_bridge_width 0.5)
				(island_removal_mode 0)
			)
			(polygon
				(pts
					(arc
						(start 51.968654 -173.800008)
						(mid 50.546254 -173.800008)
						(end 51.968654 -173.800008)
					)
				)
			)
		)
		(zone
			(layers "F.Cu" "B.Cu" "In1.Cu" "In2.Cu" "In3.Cu" "In4.Cu" "In5.Cu" "In6.Cu")
			(hatch none 0.5)
			(connect_pads
				(clearance 0)
			)
			(min_thickness 0.25)
			(keepout
				(tracks not_allowed)
				(vias allowed)
				(pads allowed)
				(copperpour not_allowed)
				(footprints allowed)
			)
			(placement
				(enabled no)
				(sheetname "")
			)
			(fill
				(thermal_gap 0.5)
				(thermal_bridge_width 0.5)
				(island_removal_mode 0)
			)
			(polygon
				(pts
					(arc
						(start 58.013854 -173.800008)
						(mid 56.591454 -173.800008)
						(end 58.013854 -173.800008)
					)
				)
			)
		)
	)
	(footprint ""
		(layer "F.Cu")
		(at 213.221316 -122.3391 90)
		(property "Reference" "C250"
			(at 0 0 90)
			(layer "F.SilkS")
			(hide yes)
			(effects
				(font
					(size 1.27 1.27)
				)
			)
		)
		(property "Value" "SC10U6D3V5KX-4GP"
			(at -0.0762 -6.1214 90)
			(unlocked yes)
			(layer "F.Fab")
			(hide yes)
			(effects
				(font
					(size 1.016 1.016)
					(thickness 0.1524)
				)
			)
		)
		(property "Device Type" "C805H58"
			(at -0.0762 -8.1534 90)
			(unlocked yes)
			(layer "F.Fab")
			(hide yes)
			(effects
				(font
					(size 1.016 1.016)
					(thickness 0.1524)
				)
			)
		)
		(duplicate_pad_numbers_are_jumpers no)
		(fp_line
			(start 0.635 0)
			(end -0.635 0)
			(stroke
				(width 0.508)
				(type default)
			)
			(layer "F.SilkS")
		)
		(fp_rect
			(start -0.9652 1.778)
			(end 0.9652 -1.778)
			(stroke
				(width 0)
				(type default)
			)
			(fill no)
			(layer "F.CrtYd")
		)
		(fp_poly
			(pts
				(xy -0.9652 -1.778) (xy 0.9652 -1.778) (xy 0.9652 1.778) (xy -0.9652 1.778)
			)
			(stroke
				(width 0)
				(type default)
			)
			(fill no)
			(layer "F.Fab")
		)
		(pad "1" smd rect
			(at 0 -0.9652 90)
			(size 1.397 1.143)
			(layers "F.Cu" "F.Mask" "F.Paste")
			(net "P1V5_OUT")
		)
		(pad "2" smd rect
			(at 0 0.9652 90)
			(size 1.397 1.143)
			(layers "F.Cu" "F.Mask" "F.Paste")
			(net "GND")
		)
	)
	(footprint ""
		(layer "F.Cu")
		(at 172.942504 -140.215366 -90)
		(property "Reference" "C153"
			(at 0 0 270)
			(layer "F.SilkS")
			(hide yes)
			(effects
				(font
					(size 1.27 1.27)
				)
			)
		)
		(property "Value" "SC10U16V5KX-7-GP-U"
			(at -0.0762 -6.1214 270)
			(unlocked yes)
			(layer "F.Fab")
			(hide yes)
			(effects
				(font
					(size 1.016 1.016)
					(thickness 0.1524)
				)
			)
		)
		(property "Device Type" "C805H58"
			(at -0.0762 -8.1534 270)
			(unlocked yes)
			(layer "F.Fab")
			(hide yes)
			(effects
				(font
					(size 1.016 1.016)
					(thickness 0.1524)
				)
			)
		)
		(duplicate_pad_numbers_are_jumpers no)
		(fp_line
			(start 0.635 0)
			(end -0.635 0)
			(stroke
				(width 0.508)
				(type default)
			)
			(layer "F.SilkS")
		)
		(fp_rect
			(start -0.9652 1.778)
			(end 0.9652 -1.778)
			(stroke
				(width 0)
				(type default)
			)
			(fill no)
			(layer "F.CrtYd")
		)
		(fp_poly
			(pts
				(xy -0.9652 -1.778) (xy 0.9652 -1.778) (xy 0.9652 1.778) (xy -0.9652 1.778)
			)
			(stroke
				(width 0)
				(type default)
			)
			(fill no)
			(layer "F.Fab")
		)
		(pad "1" smd rect
			(at 0 -0.9652 270)
			(size 1.397 1.143)
			(layers "F.Cu" "F.Mask" "F.Paste")
			(net "P12V_STBY_VIN_PU1")
		)
		(pad "2" smd rect
			(at 0 0.9652 270)
			(size 1.397 1.143)
			(layers "F.Cu" "F.Mask" "F.Paste")
			(net "GND")
		)
	)
	(footprint ""
		(layer "F.Cu")
		(at 176.9364 -63.3476 -90)
		(property "Reference" "R574"
			(at 0 0 270)
			(layer "F.SilkS")
			(hide yes)
			(effects
				(font
					(size 1.27 1.27)
				)
			)
		)
		(property "Value" "10KR2F-2-GP"
			(at 0.064008 -3.993896 270)
			(unlocked yes)
			(layer "F.Fab")
			(hide yes)
			(effects
				(font
					(size 1.016 1.016)
					(thickness 0.1524)
				)
			)
		)
		(property "Device Type" "R402H16"
			(at 0.064008 -5.517896 270)
			(unlocked yes)
			(layer "F.Fab")
			(hide yes)
			(effects
				(font
					(size 1.016 1.016)
					(thickness 0.1524)
				)
			)
		)
		(duplicate_pad_numbers_are_jumpers no)
		(fp_line
			(start -0.508 -0.9398)
			(end -0.508 0.9398)
			(stroke
				(width 0.1524)
				(type default)
			)
			(layer "F.SilkS")
		)
		(fp_line
			(start 0.508 -0.9398)
			(end -0.508 -0.9398)
			(stroke
				(width 0.1524)
				(type default)
			)
			(layer "F.SilkS")
		)
		(fp_rect
			(start -0.508 0.9398)
			(end 0.508 -0.9398)
			(stroke
				(width 0)
				(type default)
			)
			(fill no)
			(layer "F.CrtYd")
		)
		(fp_rect
			(start -0.508 0.9398)
			(end 0.508 -0.9398)
			(stroke
				(width 0)
				(type default)
			)
			(fill no)
			(layer "F.Fab")
		)
		(pad "1" smd custom
			(at 0 -0.4445 270)
			(size 0.1397 0.1397)
			(layers "F.Cu" "F.Mask" "F.Paste")
			(net "GND")
			(options
				(clearance outline)
				(anchor circle)
			)
			(primitives
				(gr_poly
					(pts
						(arc
							(start -0.1778 -0.2794)
							(mid -0.249642 -0.249642)
							(end -0.2794 -0.1778)
						)
						(arc
							(start -0.2794 0.1778)
							(mid -0.249642 0.249642)
							(end -0.1778 0.2794)
						)
						(arc
							(start 0.1778 0.2794)
							(mid 0.249642 0.249642)
							(end 0.2794 0.1778)
						)
						(arc
							(start 0.2794 -0.1778)
							(mid 0.249642 -0.249642)
							(end 0.1778 -0.2794)
						)
					)
					(width 0)
					(fill yes)
				)
			)
		)
		(pad "2" smd custom
			(at 0 0.4445 270)
			(size 0.1397 0.1397)
			(layers "F.Cu" "F.Mask" "F.Paste")
			(net "IOC_CLK_SEL0")
			(options
				(clearance outline)
				(anchor circle)
			)
			(primitives
				(gr_poly
					(pts
						(arc
							(start -0.1778 -0.2794)
							(mid -0.249642 -0.249642)
							(end -0.2794 -0.1778)
						)
						(arc
							(start -0.2794 0.1778)
							(mid -0.249642 0.249642)
							(end -0.1778 0.2794)
						)
						(arc
							(start 0.1778 0.2794)
							(mid 0.249642 0.249642)
							(end 0.2794 0.1778)
						)
						(arc
							(start 0.2794 -0.1778)
							(mid 0.249642 -0.249642)
							(end 0.1778 -0.2794)
						)
					)
					(width 0)
					(fill yes)
				)
			)
		)
	)
	(footprint ""
		(layer "F.Cu")
		(at 83.358228 -94.937072 90)
		(property "Reference" "VIA16"
			(at 0 0 90)
			(layer "F.SilkS")
			(hide yes)
			(effects
				(font
					(size 1.27 1.27)
				)
			)
		)
		(property "Value" "85OHM-8L-1D6MM-L16L18-GP"
			(at 4.064 0.6096 90)
			(unlocked yes)
			(layer "F.Fab")
			(hide yes)
			(effects
				(font
					(size 1.016 1.016)
					(thickness 0.1524)
				)
			)
		)
		(property "Device Type" "VIA-PCIE-4P-368076"
			(at 4.064 -0.9144 90)
			(unlocked yes)
			(layer "F.Fab")
			(hide yes)
			(effects
				(font
					(size 1.016 1.016)
					(thickness 0.1524)
				)
			)
		)
		(duplicate_pad_numbers_are_jumpers no)
		(fp_rect
			(start -1.8415 0.381)
			(end 1.8415 -0.381)
			(stroke
				(width 0)
				(type default)
			)
			(fill no)
			(layer "F.CrtYd")
		)
		(fp_rect
			(start -1.8415 0.381)
			(end 1.8415 -0.381)
			(stroke
				(width 0)
				(type default)
			)
			(fill no)
			(layer "F.Fab")
		)
		(pad "1" thru_hole circle
			(at -1.4605 0 90)
			(size 0.508 0.508)
			(drill 0.254)
			(layers "*.Cu" "*.Mask")
			(remove_unused_layers no)
			(net "GND")
			(clearance 0.127)
			(thermal_gap 0.127)
		)
		(pad "2" thru_hole circle
			(at -0.4445 0 90)
			(size 0.508 0.508)
			(drill 0.254)
			(layers "*.Cu" "*.Mask")
			(remove_unused_layers no)
			(net "PCIE_IOM_TO_COMP_23_DP")
			(clearance 0.127)
			(thermal_gap 0.127)
		)
		(pad "3" thru_hole circle
			(at 0.4445 0 90)
			(size 0.508 0.508)
			(drill 0.254)
			(layers "*.Cu" "*.Mask")
			(remove_unused_layers no)
			(net "PCIE_IOM_TO_COMP_23_DN")
			(clearance 0.127)
			(thermal_gap 0.127)
		)
		(pad "4" thru_hole circle
			(at 1.4605 0 90)
			(size 0.508 0.508)
			(drill 0.254)
			(layers "*.Cu" "*.Mask")
			(remove_unused_layers no)
			(net "GND")
			(clearance 0.127)
			(thermal_gap 0.127)
		)
	)
	(footprint ""
		(layer "F.Cu")
		(at 208.055972 -64.9732 90)
		(property "Reference" "C321"
			(at 0 0 90)
			(layer "F.SilkS")
			(hide yes)
			(effects
				(font
					(size 1.27 1.27)
				)
			)
		)
		(property "Value" "SCD01U16V1KX-GP"
			(at -2.8321 -1.7399 90)
			(unlocked yes)
			(layer "F.Fab")
			(hide yes)
			(effects
				(font
					(size 1.016 1.016)
					(thickness 0.1524)
				)
			)
		)
		(property "Device Type" "C0201H13"
			(at -2.8321 -3.2639 90)
			(unlocked yes)
			(layer "F.Fab")
			(hide yes)
			(effects
				(font
					(size 1.016 1.016)
					(thickness 0.1524)
				)
			)
		)
		(duplicate_pad_numbers_are_jumpers no)
		(fp_rect
			(start -0.2794 0.6477)
			(end 0.2794 -0.6477)
			(stroke
				(width 0)
				(type default)
			)
			(fill no)
			(layer "F.CrtYd")
		)
		(fp_rect
			(start -0.2794 0.6477)
			(end 0.2794 -0.6477)
			(stroke
				(width 0)
				(type default)
			)
			(fill no)
			(layer "F.Fab")
		)
		(pad "1" smd custom
			(at 0 -0.2794 90)
			(size 0.0762 0.0762)
			(layers "F.Cu" "F.Mask" "F.Paste")
			(net "PHY_IOC_TO_CON_B_3_DP_C")
			(options
				(clearance outline)
				(anchor circle)
			)
			(primitives
				(gr_poly
					(pts
						(arc
							(start 0.1524 -0.127)
							(mid 0.137521 -0.162921)
							(end 0.1016 -0.1778)
						)
						(arc
							(start -0.1016 -0.1778)
							(mid -0.137521 -0.162921)
							(end -0.1524 -0.127)
						)
						(arc
							(start -0.1524 0.127)
							(mid -0.137521 0.162921)
							(end -0.1016 0.1778)
						)
						(arc
							(start 0.1016 0.1778)
							(mid 0.137521 0.162921)
							(end 0.1524 0.127)
						)
					)
					(width 0)
					(fill yes)
				)
			)
		)
		(pad "2" smd custom
			(at 0 0.2794 90)
			(size 0.0762 0.0762)
			(layers "F.Cu" "F.Mask" "F.Paste")
			(net "PHY_IOC_TO_CON_B_3_DP")
			(options
				(clearance outline)
				(anchor circle)
			)
			(primitives
				(gr_poly
					(pts
						(arc
							(start 0.1524 -0.127)
							(mid 0.137521 -0.162921)
							(end 0.1016 -0.1778)
						)
						(arc
							(start -0.1016 -0.1778)
							(mid -0.137521 -0.162921)
							(end -0.1524 -0.127)
						)
						(arc
							(start -0.1524 0.127)
							(mid -0.137521 0.162921)
							(end -0.1016 0.1778)
						)
						(arc
							(start 0.1016 0.1778)
							(mid 0.137521 0.162921)
							(end 0.1524 0.127)
						)
					)
					(width 0)
					(fill yes)
				)
			)
		)
	)
)
